#ISCELL
  mstr_misc dns *
  *
#ISCELL
  pure_quanta quanta_title_block_c *
  *
#ISCELL
  standard offpage *
  page169_i1
#CELL
  pure_quanta q_res *
  page169_i10
#ISCELL
  standard offpage *
  page169_i11
#ISCELL
  standard offpage *
  page169_i12
#ISCELL
  standard offpage *
  page169_i13
#CELL
  pure_quanta q_cap *
  page169_i14
#ISCELL
  pure_quanta_power universal_gnd *
  page169_i15
#CELL
  pure_quanta isl99390frztr5935 *
  page169_i16
#CELL
  pure_quanta q_res *
  page169_i17
#ISCELL
  pure_quanta_power universal_gnd *
  page169_i18
#CELL
  pure_quanta q_cap *
  page169_i19
#ISCELL
  standard offpage *
  page169_i2
#ISCELL
  pure_quanta_power vcc_core *
  page169_i20
#ISCELL
  pure_quanta_power universal_gnd *
  page169_i21
#CELL
  pure_quanta q_cap *
  page169_i22
#ISCELL
  standard offpage *
  page169_i23
#ISCELL
  pure_quanta_power universal_gnd *
  page169_i24
#ISCELL
  standard offpage *
  page169_i25
#CELL
  pure_quanta isl99390frztr5935 *
  page169_i26
#ISCELL
  pure_quanta_power universal_gnd *
  page169_i27
#CELL
  pure_quanta q_res *
  page169_i28
#ISCELL
  pure_quanta_power universal_gnd *
  page169_i29
#CELL
  pure_quanta q_res *
  page169_i3
#CELL
  pure_quanta q_res *
  page169_i30
#CELL
  pure_quanta q_cap *
  page169_i31
#CELL
  pure_quanta q_res *
  page169_i32
#CELL
  pure_quanta q_cap *
  page169_i33
#CELL
  pure_quanta q_cap *
  page169_i34
#ISCELL
  pure_quanta_power universal_gnd *
  page169_i35
#CELL
  pure_quanta q_cap *
  page169_i36
#CELL
  pure_quanta q_cap *
  page169_i37
#ISCELL
  pure_quanta_power universal_gnd *
  page169_i38
#CELL
  pure_quanta q_cap *
  page169_i39
#CELL
  pure_quanta q_res *
  page169_i4
#ISCELL
  pure_quanta_power vcc_core *
  page169_i40
#ISCELL
  pure_quanta_power universal_gnd *
  page169_i41
#CELL
  pure_quanta q_res *
  page169_i42
#CELL
  pure_quanta q_res *
  page169_i43
#ISCELL
  pure_quanta_power universal_gnd *
  page169_i44
#CELL
  pure_quanta q_cap *
  page169_i45
#CELL
  pure_quanta q_res *
  page169_i46
#ISCELL
  standard offpage *
  page169_i47
#ISCELL
  pure_quanta_power universal_gnd *
  page169_i48
#CELL
  pure_quanta q_res *
  page169_i49
#ISCELL
  pure_quanta_power vcc_core *
  page169_i5
#ISCELL
  pure_quanta_power vcc_core *
  page169_i50
#CELL
  pure_quanta q_cap *
  page169_i51
#CELL
  pure_quanta q_cap *
  page169_i52
#CELL
  pure_quanta q_cap *
  page169_i53
#CELL
  pure_quanta q_cap *
  page169_i54
#CELL
  pure_quanta q_res *
  page169_i55
#ISCELL
  standard offpage *
  page169_i56
#CELL
  pure_quanta q_cap *
  page169_i57
#CELL
  pure_quanta q_cap *
  page169_i58
#CELL
  pure_quanta q_cap *
  page169_i59
#ISCELL
  pure_quanta_power vcc_core *
  page169_i6
#ISCELL
  standard offpage *
  page169_i60
#CELL
  pure_quanta q_cap *
  page169_i61
#CELL
  pure_quanta q_inductor4p_14 *
  page169_i62
#ISCELL
  standard offpage *
  page169_i63
#CELL
  pure_quanta q_capp *
  page169_i64
#CELL
  pure_quanta q_capp *
  page169_i65
#CELL
  pure_quanta q_capp *
  page169_i66
#CELL
  pure_quanta q_capp *
  page169_i67
#CELL
  pure_quanta q_cap *
  page169_i68
#ISCELL
  pure_quanta_power universal_gnd *
  page169_i69
#ISCELL
  pure_quanta_power universal_gnd *
  page169_i7
#CELL
  pure_quanta q_cap *
  page169_i70
#ISCELL
  pure_quanta_power vcc_core *
  page169_i71
#ISCELL
  pure_quanta_power universal_gnd *
  page169_i72
#CELL
  pure_quanta q_capp *
  page169_i73
#ISCELL
  pure_quanta_power vcc_core *
  page169_i74
#ISCELL
  pure_quanta_power universal_gnd *
  page169_i75
#CELL
  pure_quanta q_cap *
  page169_i76
#CELL
  pure_quanta q_inductor4p_14 *
  page169_i77
#ISCELL
  pure_quanta_power universal_gnd *
  page169_i78
#CELL
  pure_quanta q_capp *
  page169_i79
#CELL
  pure_quanta q_cap *
  page169_i8
#ISCELL
  pure_quanta_power vcc_core *
  page169_i80
#CELL
  pure_quanta q_capp *
  page169_i81
#CELL
  pure_quanta q_inductor *
  page169_i82
#ISCELL
  pure_quanta_power universal_gnd *
  page169_i83
#ISCELL
  standard offpage *
  page169_i84
#CELL
  pure_quanta q_cap *
  page169_i85
#ISCELL
  pure_quanta_power vcc_core *
  page169_i86
#CELL
  pure_quanta q_cap *
  page169_i87
#CELL
  pure_quanta q_cap *
  page169_i88
#CELL
  pure_quanta q_cap *
  page169_i89
#ISCELL
  pure_quanta_power universal_gnd *
  page169_i9
#CELL
  pure_quanta q_res *
  page169_i90
#ISCELL
  pure_quanta_power vcc_core *
  page169_i91
